# S9S_MB_2U (Grand Teton) — schematic netlist excerpt (pin names and nets, part order shuffled) for the footprints in the layout excerpt that follows; sources: Cadence DE-HDL packaged netlist, KiCad conversion of 03242023_DA0F0TMBIJ0_F0T_Motherboard_J_brd_V01_OCP.brd

J25  SCONN288_ADR50017P130CC  SCONN288_ADR50017-P130CC IO  pkg DDR288S_1-1VXB  page 106
  VIN_BULK0  = P12V_S3_AUX_CPU1_NVDIMM
  RFU0  = TP_CHE_CPU1_DIMM1_FRU_0
  VIN_MGMT  = P3V3_AUX
  HSCL  = I3C_SPD_DDREFGH_CPU1_LVC1_SCL_R
  HSDA  = I3C_SPD_DDREFGH_CPU1_LVC1_SDA
  VSS0  = GND
  DQ0_A  = M_E_CPU1_SA_DQ<0>
  VSS1  = GND
  DQ1_A  = M_E_CPU1_SA_DQ<1>
  VSS2  = GND
  DQS0_A_T  = M_E_CPU1_SA_DQS_DP<0>
  DQS0_A_C  = M_E_CPU1_SA_DQS_DN<0>
  VSS3  = GND
  DQ4_A  = M_E_CPU1_SA_DQ<4>
  VSS4  = GND
  DQ5_A  = M_E_CPU1_SA_DQ<5>
  VSS5  = GND
  DQ8_A  = M_E_CPU1_SA_DQ<8>
  VSS6  = GND
  DQ9_A  = M_E_CPU1_SA_DQ<9>
  VSS7  = GND
  DQS1_A_T  = M_E_CPU1_SA_DQS_DP<1>
  DQS1_A_C  = M_E_CPU1_SA_DQS_DN<1>
  VSS8  = GND
  DQ12_A  = M_E_CPU1_SA_DQ<12>
  VSS9  = GND
  DQ13_A  = M_E_CPU1_SA_DQ<13>
  VSS10  = GND
  DQ16_A  = M_E_CPU1_SA_DQ<16>
  VSS11  = GND
  DQ17_A  = M_E_CPU1_SA_DQ<17>
  VSS12  = GND
  DQS2_A_T  = M_E_CPU1_SA_DQS_DP<2>
  DQS2_A_C  = M_E_CPU1_SA_DQS_DN<2>
  VSS13  = GND
  DQ20_A  = M_E_CPU1_SA_DQ<20>
  VSS14  = GND
  DQ21_A  = M_E_CPU1_SA_DQ<21>
  VSS15  = GND
  DQ24_A  = M_E_CPU1_SA_DQ<24>
  VSS16  = GND
  DQ25_A  = M_E_CPU1_SA_DQ<25>
  VSS17  = GND
  DQS3_A_T  = M_E_CPU1_SA_DQS_DP<3>
  DQS3_A_C  = M_E_CPU1_SA_DQS_DN<3>
  VSS18  = GND
  DQ28_A  = M_E_CPU1_SA_DQ<28>
  VSS19  = GND
  DQ29_A  = M_E_CPU1_SA_DQ<29>
  VSS20  = GND
  CB0_A  = M_E_CPU1_SA_CB<0>
  VSS21  = GND
  CB1_A  = M_E_CPU1_SA_CB<1>
  VSS22  = GND
  DQS4_A_T  = M_E_CPU1_SA_DQS_DP<4>
  DQS4_A_C  = M_E_CPU1_SA_DQS_DN<4>
  VSS23  = GND
  CB4_A  = M_E_CPU1_SA_CB<4>
  VSS24  = GND
  CB5_A  = M_E_CPU1_SA_CB<5>
  VSS25  = GND
  ALERT_N  = M_E_CPU1_ALERT_N
  VSS26  = GND
  CS0_A_N  = M_E_CPU1_SA_CS_N<0>
  VSS27  = GND
  CA0_A  = M_E_CPU1_SA_CA<0>
  VSS28  = GND
  CA2_A  = M_E_CPU1_SA_CA<2>
  VSS29  = GND
  CA4_A  = M_E_CPU1_SA_CA<4>
  VSS30  = GND
  CA6_A  = M_E_CPU1_SA_CA<6>
  VSS31  = GND
  PAR_A  = M_E_CPU1_SA_PAR
  VSS32  = GND
  CA0_B  = M_E_CPU1_SB_CA<0>
  VSS33  = GND
  CA2_B  = M_E_CPU1_SB_CA<2>
  VSS34  = GND
  CA4_B  = M_E_CPU1_SB_CA<4>
  VSS35  = GND
  CA6_B  = M_E_CPU1_SB_CA<6>
  VSS36  = GND
  CS0_B_N  = M_E_CPU1_SB_CS_N<0>
  VSS37  = GND
  \lbd||rsp_a_n\  = M_E_CPU1_SA_RSP<0>
  \lbs||rsp_b_n\  = M_E_CPU1_SB_RSP<0>
  VSS38  = GND
  CB4_B  = M_E_CPU1_SB_CB<4>
  VSS39  = GND
  CB5_B  = M_E_CPU1_SB_CB<5>
  VSS40  = GND
  \dqs9_b_t||tdqs9_b_t||dbi4_b_n\  = M_E_CPU1_SB_DQS_DP<9>
  \dqs9_b_c||tdqs9_b_c\  = M_E_CPU1_SB_DQS_DN<9>
  VSS41  = GND
  CB0_B  = M_E_CPU1_SB_CB<0>
  VSS42  = GND
  CB1_B  = M_E_CPU1_SB_CB<1>
  VSS43  = GND
  DQ0_B  = M_E_CPU1_SB_DQ<0>
  VSS44  = GND
  DQ1_B  = M_E_CPU1_SB_DQ<1>
  VSS45  = GND
  DQS0_B_T  = M_E_CPU1_SB_DQS_DP<0>
  DQS0_B_C  = M_E_CPU1_SB_DQS_DN<0>
  VSS46  = GND
  DQ4_B  = M_E_CPU1_SB_DQ<4>
  VSS47  = GND
  DQ5_B  = M_E_CPU1_SB_DQ<5>
  VSS48  = GND
  DQ8_B  = M_E_CPU1_SB_DQ<8>
  VSS49  = GND
  DQ9_B  = M_E_CPU1_SB_DQ<9>
  VSS50  = GND
  DQS1_B_T  = M_E_CPU1_SB_DQS_DP<1>
  DQS1_B_C  = M_E_CPU1_SB_DQS_DN<1>
  VSS51  = GND
  DQ12_B  = M_E_CPU1_SB_DQ<12>
  VSS52  = GND
  DQ13_B  = M_E_CPU1_SB_DQ<13>
  VSS53  = GND
  DQ16_B  = M_E_CPU1_SB_DQ<16>
  VSS54  = GND
  DQ17_B  = M_E_CPU1_SB_DQ<17>
  VSS55  = GND
  DQS2_B_T  = M_E_CPU1_SB_DQS_DP<2>
  DQS2_B_C  = M_E_CPU1_SB_DQS_DN<2>
  VSS56  = GND
  DQ20_B  = M_E_CPU1_SB_DQ<20>
  VSS57  = GND
  DQ21_B  = M_E_CPU1_SB_DQ<21>
  VSS58  = GND
  DQ24_B  = M_E_CPU1_SB_DQ<24>
  VSS59  = GND
  DQ25_B  = M_E_CPU1_SB_DQ<25>
  VSS60  = GND
  DQS3_B_T  = M_E_CPU1_SB_DQS_DP<3>
  DQS3_B_C  = M_E_CPU1_SB_DQS_DN<3>
  VSS61  = GND
  DQ28_B  = M_E_CPU1_SB_DQ<28>
  VSS62  = GND
  DQ29_B  = M_E_CPU1_SB_DQ<29>
  VSS63  = GND
  RFU1  = TP_CHE_CPU1_DIMM1_FRU_1
  VIN_BULK1  = P12V_S3_AUX_CPU1_NVDIMM
  VIN_BULK2  = P12V_S3_AUX_CPU1_NVDIMM
  \pwr_good||fail_n\  = PWRGD_CHE_CPU1_DIMM1
  HSA  = PD_CHE_CPU1_DIMM1_SAA
  RFU2  = TP_CHE_CPU1_DIMM1_FRU_2
  RFU3  = TP_CHE_CPU1_DIMM1_FRU_3
  VSS64  = GND
  DQ2_A  = M_E_CPU1_SA_DQ<2>
  VSS65  = GND
  DQ3_A  = M_E_CPU1_SA_DQ<3>
  VSS66  = GND
  \dqs5_a_c||tdqs5_a_c||dqs5_a_t||tdqs5_a_t\  = M_E_CPU1_SA_DQS_DN<5>
  \dqs5_a_t||tdqs5_a_t\  = M_E_CPU1_SA_DQS_DP<5>
  VSS67  = GND
  DQ6_A  = M_E_CPU1_SA_DQ<6>
  VSS68  = GND
  DQ7_A  = M_E_CPU1_SA_DQ<7>
  VSS69  = GND
  DQ10_A  = M_E_CPU1_SA_DQ<10>
  VSS70  = GND
  DQ11_A  = M_E_CPU1_SA_DQ<11>
  VSS71  = GND
  \dqs6_a_c||tdqs6_a_c||dqs6_a_t||tdqs6_a_t\  = M_E_CPU1_SA_DQS_DN<6>
  \dqs6_a_t||tdqs6_a_t\  = M_E_CPU1_SA_DQS_DP<6>
  VSS72  = GND
  DQ14_A  = M_E_CPU1_SA_DQ<14>
  VSS73  = GND
  DQ15_A  = M_E_CPU1_SA_DQ<15>
  VSS74  = GND
  DQ18_A  = M_E_CPU1_SA_DQ<18>
  VSS75  = GND
  DQ19_A  = M_E_CPU1_SA_DQ<19>
  VSS76  = GND
  \dqs7_a_c||tdqs7_a_c\  = M_E_CPU1_SA_DQS_DN<7>
  \dqs7_a_t||tdqs7_a_t\  = M_E_CPU1_SA_DQS_DP<7>
  VSS77  = GND
  DQ22_A  = M_E_CPU1_SA_DQ<22>
  VSS78  = GND
  DQ23_A  = M_E_CPU1_SA_DQ<23>
  VSS79  = GND
  DQ26_A  = M_E_CPU1_SA_DQ<26>
  VSS80  = GND
  DQ27_A  = M_E_CPU1_SA_DQ<27>
  VSS81  = GND
  \dqs8_a_c||tdqs8_a_c\  = M_E_CPU1_SA_DQS_DN<8>
  \dqs8_a_t||tdqs8_a_t\  = M_E_CPU1_SA_DQS_DP<8>
  VSS82  = GND
  DQ30_A  = M_E_CPU1_SA_DQ<30>
  VSS83  = GND
  DQ31_A  = M_E_CPU1_SA_DQ<31>
  VSS84  = GND
  CB2_A  = M_E_CPU1_SA_CB<2>
  VSS85  = GND
  CB3_A  = M_E_CPU1_SA_CB<3>
  VSS86  = GND
  \dqs9_a_c||tdqs9_a_c\  = M_E_CPU1_SA_DQS_DN<9>
  \dqs9_a_t||tdqs9_a_t\  = M_E_CPU1_SA_DQS_DP<9>
  VSS87  = GND
  CB6_A  = M_E_CPU1_SA_CB<6>
  VSS88  = GND
  CB7_A  = M_E_CPU1_SA_CB<7>
  VSS89  = GND
  RESET_N  = RST_M_EF_CPU1_FPGA_N
  VSS90  = GND
  CS1_A_N  = M_E_CPU1_SA_CS_N<1>
  VSS91  = GND
  CA1_A  = M_E_CPU1_SA_CA<1>
  VSS92  = GND
  CA3_A  = M_E_CPU1_SA_CA<3>
  VSS93  = GND
  CA5_A  = M_E_CPU1_SA_CA<5>
  VSS94  = GND
  CK_T  = M_E_CPU1_CLK_DP<0>
  CK_C  = M_E_CPU1_CLK_DN<0>
  VSS95  = GND
  RFU4  = TP_CHE_CPU1_DIMM1_FRU_4
  CA1_B  = M_E_CPU1_SB_CA<1>
  VSS96  = GND
  CA3_B  = M_E_CPU1_SB_CA<3>
  VSS97  = GND
  CA5_B  = M_E_CPU1_SB_CA<5>
  VSS98  = GND
  PAR_B  = M_E_CPU1_SB_PAR
  VSS99  = GND
  CS1_B_N  = M_E_CPU1_SB_CS_N<1>
  VSS100  = GND
  RFU5  = TP_CHE_CPU1_DIMM1_FRU_5
  RFU6  = TP_CHE_CPU1_DIMM1_FRU_6
  VSS101  = GND
  CB6_B  = M_E_CPU1_SB_CB<6>
  VSS102  = GND
  CB7_B  = M_E_CPU1_SB_CB<7>
  VSS103  = GND
  DQS4_B_C  = M_E_CPU1_SB_DQS_DN<4>
  DQS4_B_T  = M_E_CPU1_SB_DQS_DP<4>
  VSS104  = GND
  CB2_B  = M_E_CPU1_SB_CB<2>
  VSS105  = GND
  CB3_B  = M_E_CPU1_SB_CB<3>
  VSS106  = GND
  DQ2_B  = M_E_CPU1_SB_DQ<2>
  VSS107  = GND
  DQ3_B  = M_E_CPU1_SB_DQ<3>
  VSS108  = GND
  \dqs5_b_c||tdqs5_b_c\  = M_E_CPU1_SB_DQS_DN<5>
  \dqs5_b_t||tdqs5_b_t\  = M_E_CPU1_SB_DQS_DP<5>
  VSS109  = GND
  DQ6_B  = M_E_CPU1_SB_DQ<6>
  VSS110  = GND
  DQ7_B  = M_E_CPU1_SB_DQ<7>
  VSS111  = GND
  DQ10_B  = M_E_CPU1_SB_DQ<10>
  VSS112  = GND
  DQ11_B  = M_E_CPU1_SB_DQ<11>
  VSS113  = GND
  \dqs6_b_c||tdqs6_b_c\  = M_E_CPU1_SB_DQS_DN<6>
  \dqs6_b_t||tdqs6_b_t\  = M_E_CPU1_SB_DQS_DP<6>
  VSS114  = GND
  DQ14_B  = M_E_CPU1_SB_DQ<14>
  VSS115  = GND
  DQ15_B  = M_E_CPU1_SB_DQ<15>
  VSS116  = GND
  DQ18_B  = M_E_CPU1_SB_DQ<18>
  VSS117  = GND
  DQ19_B  = M_E_CPU1_SB_DQ<19>
  VSS118  = GND
  \dqs7_b_c||tdqs7_b_c\  = M_E_CPU1_SB_DQS_DN<7>
  \dqs7_b_t||tdqs7_b_t\  = M_E_CPU1_SB_DQS_DP<7>
  VSS119  = GND
  DQ22_B  = M_E_CPU1_SB_DQ<22>
  VSS120  = GND
  DQ23_B  = M_E_CPU1_SB_DQ<23>
  VSS121  = GND
  DQ26_B  = M_E_CPU1_SB_DQ<26>
  VSS122  = GND
  DQ27_B  = M_E_CPU1_SB_DQ<27>
  VSS123  = GND
  \dqs8_b_c||tdqs8_b_c\  = M_E_CPU1_SB_DQS_DN<8>
  \dqs8_b_t||tdqs8_b_t\  = M_E_CPU1_SB_DQS_DP<8>
  VSS124  = GND
  DQ30_B  = M_E_CPU1_SB_DQ<30>
  VSS125  = GND
  DQ31_B  = M_E_CPU1_SB_DQ<31>
  VSS126  = GND
  G1  = GND
  G2  = GND
  G3  = GND

(kicad_pcb
	(version 20260206)
	(generator "pcbnew")
	(generator_version "10.0")
	(general
		(thickness 1.6)
		(legacy_teardrops no)
	)
	(paper "A4")
	(title_block
		(title "03242023_DA0F0TMBIJ0_F0T_Motherboard_J_brd_V01_OCP.brd")
		(comment 1 "Grand Teton / footprint 2539 of 6105 (J25), pads 229-274 of 291")
	)
	(layers
		(0 "F.Cu" signal "TOP")
		(4 "In1.Cu" signal "GND")
		(6 "In2.Cu" signal "IN1")
		(8 "In3.Cu" signal "GND1")
		(10 "In4.Cu" signal "IN2")
		(12 "In5.Cu" signal "GND2")
		(14 "In6.Cu" signal "IN3")
		(16 "In7.Cu" signal "GND3")
		(18 "In8.Cu" signal "VCC")
		(20 "In9.Cu" signal "VCC1")
		(22 "In10.Cu" signal "GND4")
		(24 "In11.Cu" signal "IN4")
		(26 "In12.Cu" signal "GND5")
		(28 "In13.Cu" signal "IN5")
		(30 "In14.Cu" signal "GND6")
		(32 "In15.Cu" signal "IN6")
		(34 "In16.Cu" signal "GND7")
		(2 "B.Cu" signal "BOTTOM")
		(9 "F.Adhes" user "F.Adhesive")
		(11 "B.Adhes" user "B.Adhesive")
		(13 "F.Paste" user "Package Geometry/Pastemask Top")
		(15 "B.Paste" user "Package Geometry/Pastemask Bottom")
		(5 "F.SilkS" user "Ref Des/Silkscreen Top")
		(7 "B.SilkS" user "Ref Des/Silkscreen Bottom")
		(1 "F.Mask" user "Board Geometry/Soldermask Top")
		(3 "B.Mask" user "Board Geometry/Soldermask Bottom")
		(17 "Dwgs.User" user "User.Drawings")
		(19 "Cmts.User" user "User.Comments")
		(21 "Eco1.User" user "User.Eco1")
		(23 "Eco2.User" user "User.Eco2")
		(25 "Edge.Cuts" user "Board Geometry/Outline")
		(27 "Margin" user)
		(31 "F.CrtYd" user "Package Geometry/Place Bound Top")
		(29 "B.CrtYd" user "Package Geometry/Place Bound Bottom")
		(35 "F.Fab" user "Ref Des/Assembly Top")
		(33 "B.Fab" user "Ref Des/Assembly Bottom")
	)
	(footprint ""
		(layer "F.Cu")
		(at 168.40708 -258.091686)
		(property "Reference" "J25"
			(at -3.683 -81.702148 0)
			(unlocked yes)
			(layer "F.SilkS")
			(effects
				(font
					(size 0.7874 0.5842)
					(thickness 0.1524)
				)
				(justify left)
			)
		)
		(property "Value" ""
			(at 0 0 0)
			(layer "F.Fab")
			(effects
				(font
					(size 1.27 1.27)
				)
			)
		)
		(duplicate_pad_numbers_are_jumpers no)
		(pad "229" smd rect
			(at 2.050034 13.17498 270)
			(size 0.519938 1.4986)
			(layers "F.Cu" "F.Mask" "F.Paste")
			(net "M_E_CPU1_SB_CS_N<1>")
		)
		(pad "230" smd rect
			(at 2.050034 14.025118 270)
			(size 0.519938 1.4986)
			(layers "F.Cu" "F.Mask" "F.Paste")
			(net "GND")
		)
		(pad "231" smd rect
			(at 2.050034 14.875002 270)
			(size 0.519938 1.4986)
			(layers "F.Cu" "F.Mask" "F.Paste")
			(net "TP_CHE_CPU1_DIMM1_FRU_5")
		)
		(pad "232" smd rect
			(at 2.050034 15.724886 270)
			(size 0.519938 1.4986)
			(layers "F.Cu" "F.Mask" "F.Paste")
			(net "TP_CHE_CPU1_DIMM1_FRU_6")
		)
		(pad "233" smd rect
			(at 2.050034 16.575024 270)
			(size 0.519938 1.4986)
			(layers "F.Cu" "F.Mask" "F.Paste")
			(net "GND")
		)
		(pad "234" smd rect
			(at 2.050034 17.424908 270)
			(size 0.519938 1.4986)
			(layers "F.Cu" "F.Mask" "F.Paste")
			(net "M_E_CPU1_SB_CB<6>")
		)
		(pad "235" smd rect
			(at 2.050034 18.275046 270)
			(size 0.519938 1.4986)
			(layers "F.Cu" "F.Mask" "F.Paste")
			(net "GND")
		)
		(pad "236" smd rect
			(at 2.050034 19.12493 270)
			(size 0.519938 1.4986)
			(layers "F.Cu" "F.Mask" "F.Paste")
			(net "M_E_CPU1_SB_CB<7>")
		)
		(pad "237" smd rect
			(at 2.050034 19.975068 270)
			(size 0.519938 1.4986)
			(layers "F.Cu" "F.Mask" "F.Paste")
			(net "GND")
		)
		(pad "238" smd rect
			(at 2.050034 20.824952 270)
			(size 0.519938 1.4986)
			(layers "F.Cu" "F.Mask" "F.Paste")
			(net "M_E_CPU1_SB_DQS_DN<4>")
		)
		(pad "239" smd rect
			(at 2.050034 21.67509 270)
			(size 0.519938 1.4986)
			(layers "F.Cu" "F.Mask" "F.Paste")
			(net "M_E_CPU1_SB_DQS_DP<4>")
		)
		(pad "240" smd rect
			(at 2.050034 22.524974 270)
			(size 0.519938 1.4986)
			(layers "F.Cu" "F.Mask" "F.Paste")
			(net "GND")
		)
		(pad "241" smd rect
			(at 2.050034 23.375112 270)
			(size 0.519938 1.4986)
			(layers "F.Cu" "F.Mask" "F.Paste")
			(net "M_E_CPU1_SB_CB<2>")
		)
		(pad "242" smd rect
			(at 2.050034 24.224996 270)
			(size 0.519938 1.4986)
			(layers "F.Cu" "F.Mask" "F.Paste")
			(net "GND")
		)
		(pad "243" smd rect
			(at 2.050034 25.07488 270)
			(size 0.519938 1.4986)
			(layers "F.Cu" "F.Mask" "F.Paste")
			(net "M_E_CPU1_SB_CB<3>")
		)
		(pad "244" smd rect
			(at 2.050034 25.925018 270)
			(size 0.519938 1.4986)
			(layers "F.Cu" "F.Mask" "F.Paste")
			(net "GND")
		)
		(pad "245" smd rect
			(at 2.050034 26.774902 270)
			(size 0.519938 1.4986)
			(layers "F.Cu" "F.Mask" "F.Paste")
			(net "M_E_CPU1_SB_DQ<2>")
		)
		(pad "246" smd rect
			(at 2.050034 27.62504 270)
			(size 0.519938 1.4986)
			(layers "F.Cu" "F.Mask" "F.Paste")
			(net "GND")
		)
		(pad "247" smd rect
			(at 2.050034 28.474924 270)
			(size 0.519938 1.4986)
			(layers "F.Cu" "F.Mask" "F.Paste")
			(net "M_E_CPU1_SB_DQ<3>")
		)
		(pad "248" smd rect
			(at 2.050034 29.325062 270)
			(size 0.519938 1.4986)
			(layers "F.Cu" "F.Mask" "F.Paste")
			(net "GND")
		)
		(pad "249" smd rect
			(at 2.050034 30.174946 270)
			(size 0.519938 1.4986)
			(layers "F.Cu" "F.Mask" "F.Paste")
			(net "M_E_CPU1_SB_DQS_DN<5>")
		)
		(pad "250" smd rect
			(at 2.050034 31.025084 270)
			(size 0.519938 1.4986)
			(layers "F.Cu" "F.Mask" "F.Paste")
			(net "M_E_CPU1_SB_DQS_DP<5>")
		)
		(pad "251" smd rect
			(at 2.050034 31.874968 270)
			(size 0.519938 1.4986)
			(layers "F.Cu" "F.Mask" "F.Paste")
			(net "GND")
		)
		(pad "252" smd rect
			(at 2.050034 32.725106 270)
			(size 0.519938 1.4986)
			(layers "F.Cu" "F.Mask" "F.Paste")
			(net "M_E_CPU1_SB_DQ<6>")
		)
		(pad "253" smd rect
			(at 2.050034 33.57499 270)
			(size 0.519938 1.4986)
			(layers "F.Cu" "F.Mask" "F.Paste")
			(net "GND")
		)
		(pad "254" smd rect
			(at 2.050034 34.425128 270)
			(size 0.519938 1.4986)
			(layers "F.Cu" "F.Mask" "F.Paste")
			(net "M_E_CPU1_SB_DQ<7>")
		)
		(pad "255" smd rect
			(at 2.050034 35.275012 270)
			(size 0.519938 1.4986)
			(layers "F.Cu" "F.Mask" "F.Paste")
			(net "GND")
		)
		(pad "256" smd rect
			(at 2.050034 36.124896 270)
			(size 0.519938 1.4986)
			(layers "F.Cu" "F.Mask" "F.Paste")
			(net "M_E_CPU1_SB_DQ<10>")
		)
		(pad "257" smd rect
			(at 2.050034 36.975034 270)
			(size 0.519938 1.4986)
			(layers "F.Cu" "F.Mask" "F.Paste")
			(net "GND")
		)
		(pad "258" smd rect
			(at 2.050034 37.824918 270)
			(size 0.519938 1.4986)
			(layers "F.Cu" "F.Mask" "F.Paste")
			(net "M_E_CPU1_SB_DQ<11>")
		)
		(pad "259" smd rect
			(at 2.050034 38.675056 270)
			(size 0.519938 1.4986)
			(layers "F.Cu" "F.Mask" "F.Paste")
			(net "GND")
		)
		(pad "260" smd rect
			(at 2.050034 39.52494 270)
			(size 0.519938 1.4986)
			(layers "F.Cu" "F.Mask" "F.Paste")
			(net "M_E_CPU1_SB_DQS_DN<6>")
		)
		(pad "261" smd rect
			(at 2.050034 40.375078 270)
			(size 0.519938 1.4986)
			(layers "F.Cu" "F.Mask" "F.Paste")
			(net "M_E_CPU1_SB_DQS_DP<6>")
		)
		(pad "262" smd rect
			(at 2.050034 41.224962 270)
			(size 0.519938 1.4986)
			(layers "F.Cu" "F.Mask" "F.Paste")
			(net "GND")
		)
		(pad "263" smd rect
			(at 2.050034 42.0751 270)
			(size 0.519938 1.4986)
			(layers "F.Cu" "F.Mask" "F.Paste")
			(net "M_E_CPU1_SB_DQ<14>")
		)
		(pad "264" smd rect
			(at 2.050034 42.924984 270)
			(size 0.519938 1.4986)
			(layers "F.Cu" "F.Mask" "F.Paste")
			(net "GND")
		)
		(pad "265" smd rect
			(at 2.050034 43.775122 270)
			(size 0.519938 1.4986)
			(layers "F.Cu" "F.Mask" "F.Paste")
			(net "M_E_CPU1_SB_DQ<15>")
		)
		(pad "266" smd rect
			(at 2.050034 44.625006 270)
			(size 0.519938 1.4986)
			(layers "F.Cu" "F.Mask" "F.Paste")
			(net "GND")
		)
		(pad "267" smd rect
			(at 2.050034 45.47489 270)
			(size 0.519938 1.4986)
			(layers "F.Cu" "F.Mask" "F.Paste")
			(net "M_E_CPU1_SB_DQ<18>")
		)
		(pad "268" smd rect
			(at 2.050034 46.325028 270)
			(size 0.519938 1.4986)
			(layers "F.Cu" "F.Mask" "F.Paste")
			(net "GND")
		)
		(pad "269" smd rect
			(at 2.050034 47.174912 270)
			(size 0.519938 1.4986)
			(layers "F.Cu" "F.Mask" "F.Paste")
			(net "M_E_CPU1_SB_DQ<19>")
		)
		(pad "270" smd rect
			(at 2.050034 48.02505 270)
			(size 0.519938 1.4986)
			(layers "F.Cu" "F.Mask" "F.Paste")
			(net "GND")
		)
		(pad "271" smd rect
			(at 2.050034 48.874934 270)
			(size 0.519938 1.4986)
			(layers "F.Cu" "F.Mask" "F.Paste")
			(net "M_E_CPU1_SB_DQS_DN<7>")
		)
		(pad "272" smd rect
			(at 2.050034 49.725072 270)
			(size 0.519938 1.4986)
			(layers "F.Cu" "F.Mask" "F.Paste")
			(net "M_E_CPU1_SB_DQS_DP<7>")
		)
		(pad "273" smd rect
			(at 2.050034 50.574956 270)
			(size 0.519938 1.4986)
			(layers "F.Cu" "F.Mask" "F.Paste")
			(net "GND")
		)
		(pad "274" smd rect
			(at 2.050034 51.425094 270)
			(size 0.519938 1.4986)
			(layers "F.Cu" "F.Mask" "F.Paste")
			(net "M_E_CPU1_SB_DQ<22>")
		)
	)
)
